(kicad_pcb
	(version 20260206)
	(generator "pcbnew")
	(generator_version "10.0")
	(general
		(thickness 1.6)
		(legacy_teardrops no)
	)
	(paper "A4")
	(title_block
		(title "03242023_DA0F0TMBIJ0_F0T_Motherboard_J_brd_V01_OCP.brd")
		(comment 1 "Grand Teton / footprints 827-833 of 6105")
	)
	(layers
		(0 "F.Cu" signal "TOP")
		(4 "In1.Cu" signal "GND")
		(6 "In2.Cu" signal "IN1")
		(8 "In3.Cu" signal "GND1")
		(10 "In4.Cu" signal "IN2")
		(12 "In5.Cu" signal "GND2")
		(14 "In6.Cu" signal "IN3")
		(16 "In7.Cu" signal "GND3")
		(18 "In8.Cu" signal "VCC")
		(20 "In9.Cu" signal "VCC1")
		(22 "In10.Cu" signal "GND4")
		(24 "In11.Cu" signal "IN4")
		(26 "In12.Cu" signal "GND5")
		(28 "In13.Cu" signal "IN5")
		(30 "In14.Cu" signal "GND6")
		(32 "In15.Cu" signal "IN6")
		(34 "In16.Cu" signal "GND7")
		(2 "B.Cu" signal "BOTTOM")
		(9 "F.Adhes" user "F.Adhesive")
		(11 "B.Adhes" user "B.Adhesive")
		(13 "F.Paste" user "Package Geometry/Pastemask Top")
		(15 "B.Paste" user "Package Geometry/Pastemask Bottom")
		(5 "F.SilkS" user "Ref Des/Silkscreen Top")
		(7 "B.SilkS" user "Ref Des/Silkscreen Bottom")
		(1 "F.Mask" user "Board Geometry/Soldermask Top")
		(3 "B.Mask" user "Board Geometry/Soldermask Bottom")
		(17 "Dwgs.User" user "User.Drawings")
		(19 "Cmts.User" user "User.Comments")
		(21 "Eco1.User" user "User.Eco1")
		(23 "Eco2.User" user "User.Eco2")
		(25 "Edge.Cuts" user "Board Geometry/Outline")
		(27 "Margin" user)
		(31 "F.CrtYd" user "Package Geometry/Place Bound Top")
		(29 "B.CrtYd" user "Package Geometry/Place Bound Bottom")
		(35 "F.Fab" user "Ref Des/Assembly Top")
		(33 "B.Fab" user "Ref Des/Assembly Bottom")
	)
	(footprint ""
		(layer "F.Cu")
		(at 45.805344 -148.837396 90)
		(property "Reference" "PL23"
			(at 0.094742 -5.884164 0)
			(unlocked yes)
			(layer "F.SilkS")
			(effects
				(font
					(size 0.7874 0.5842)
					(thickness 0.1524)
				)
				(justify left)
			)
		)
		(property "Value" ""
			(at 0 0 90)
			(layer "F.Fab")
			(effects
				(font
					(size 1.27 1.27)
				)
			)
		)
		(duplicate_pad_numbers_are_jumpers no)
		(fp_line
			(start 2.249932 -2.249932)
			(end 2.249932 -1.3843)
			(stroke
				(width 0.1524)
				(type default)
			)
			(layer "F.SilkS")
		)
		(fp_line
			(start -2.249932 -2.249932)
			(end 2.249932 -2.249932)
			(stroke
				(width 0.1524)
				(type default)
			)
			(layer "F.SilkS")
		)
		(fp_line
			(start -2.249932 -1.3843)
			(end -2.249932 -2.249932)
			(stroke
				(width 0.1524)
				(type default)
			)
			(layer "F.SilkS")
		)
		(fp_line
			(start 2.249932 1.3843)
			(end 2.249932 2.249932)
			(stroke
				(width 0.1524)
				(type default)
			)
			(layer "F.SilkS")
		)
		(fp_line
			(start 2.249932 2.249932)
			(end -2.249932 2.249932)
			(stroke
				(width 0.1524)
				(type default)
			)
			(layer "F.SilkS")
		)
		(fp_line
			(start -2.249932 2.249932)
			(end -2.249932 1.3843)
			(stroke
				(width 0.1524)
				(type default)
			)
			(layer "F.SilkS")
		)
		(fp_line
			(start 2.249932 -2.249932)
			(end 2.249932 2.249932)
			(stroke
				(width 0.1)
				(type default)
			)
			(layer "F.Fab")
		)
		(fp_line
			(start -2.249932 -2.249932)
			(end 2.249932 -2.249932)
			(stroke
				(width 0.1)
				(type default)
			)
			(layer "F.Fab")
		)
		(fp_line
			(start 2.249932 2.249932)
			(end -2.249932 2.249932)
			(stroke
				(width 0.1)
				(type default)
			)
			(layer "F.Fab")
		)
		(fp_line
			(start -2.249932 2.249932)
			(end -2.249932 -2.249932)
			(stroke
				(width 0.1)
				(type default)
			)
			(layer "F.Fab")
		)
		(pad "1" smd rect
			(at -1.82499 0 90)
			(size 1.0668 2.5146)
			(layers "F.Cu" "F.Mask" "F.Paste")
			(net "P12V_AUX")
		)
		(pad "2" smd rect
			(at 1.82499 0 90)
			(size 1.0668 2.5146)
			(layers "F.Cu" "F.Mask" "F.Paste")
			(net "SW_P12V_PVCCINFAON_CPU1_FLT")
		)
	)
	(footprint ""
		(layer "F.Cu")
		(at 24.684482 -397.687292 90)
		(property "Reference" "R4666"
			(at 0 0 90)
			(layer "F.SilkS")
			(hide yes)
			(effects
				(font
					(size 1.27 1.27)
				)
			)
		)
		(property "Value" ""
			(at 0 0 90)
			(layer "F.Fab")
			(effects
				(font
					(size 1.27 1.27)
				)
			)
		)
		(duplicate_pad_numbers_are_jumpers no)
		(fp_line
			(start -0.7874 -0.4064)
			(end 0.7874 -0.4064)
			(stroke
				(width 0.1524)
				(type default)
			)
			(layer "F.SilkS")
		)
		(fp_line
			(start 0.7874 0.4064)
			(end -0.002032 0.4064)
			(stroke
				(width 0.1524)
				(type default)
			)
			(layer "F.SilkS")
		)
		(fp_line
			(start -0.7874 0.4064)
			(end -0.7874 -0.4064)
			(stroke
				(width 0.1524)
				(type default)
			)
			(layer "F.SilkS")
		)
		(fp_line
			(start -0.12065 -0.305054)
			(end -0.12065 -0.2794)
			(stroke
				(width 0.1)
				(type default)
			)
			(layer "F.Fab")
		)
		(fp_line
			(start -0.67945 -0.305054)
			(end -0.12065 -0.305054)
			(stroke
				(width 0.1)
				(type default)
			)
			(layer "F.Fab")
		)
		(fp_line
			(start 0.67945 -0.3048)
			(end 0.67945 0.3048)
			(stroke
				(width 0.1)
				(type default)
			)
			(layer "F.Fab")
		)
		(fp_line
			(start 0.12065 -0.3048)
			(end 0.67945 -0.3048)
			(stroke
				(width 0.1)
				(type default)
			)
			(layer "F.Fab")
		)
		(fp_line
			(start 0.12065 -0.2794)
			(end 0.12065 -0.3048)
			(stroke
				(width 0.1)
				(type default)
			)
			(layer "F.Fab")
		)
		(fp_line
			(start -0.12065 -0.2794)
			(end 0.12065 -0.2794)
			(stroke
				(width 0.1)
				(type default)
			)
			(layer "F.Fab")
		)
		(fp_line
			(start 0.120396 0.2794)
			(end -0.12065 0.2794)
			(stroke
				(width 0.1)
				(type default)
			)
			(layer "F.Fab")
		)
		(fp_line
			(start -0.12065 0.2794)
			(end -0.12065 0.3048)
			(stroke
				(width 0.1)
				(type default)
			)
			(layer "F.Fab")
		)
		(fp_line
			(start 0.67945 0.3048)
			(end 0.120396 0.3048)
			(stroke
				(width 0.1)
				(type default)
			)
			(layer "F.Fab")
		)
		(fp_line
			(start 0.120396 0.3048)
			(end 0.120396 0.2794)
			(stroke
				(width 0.1)
				(type default)
			)
			(layer "F.Fab")
		)
		(fp_line
			(start -0.12065 0.3048)
			(end -0.67945 0.3048)
			(stroke
				(width 0.1)
				(type default)
			)
			(layer "F.Fab")
		)
		(fp_line
			(start -0.67945 0.3048)
			(end -0.67945 -0.305054)
			(stroke
				(width 0.1)
				(type default)
			)
			(layer "F.Fab")
		)
		(pad "1" smd rect
			(at -0.40005 0 270)
			(size 0.4572 0.508)
			(layers "F.Cu" "F.Mask" "F.Paste")
			(net "P2E_MB_BMC_RX_DN<0>")
		)
		(pad "2" smd rect
			(at 0.40005 0 270)
			(size 0.4572 0.508)
			(layers "F.Cu" "F.Mask" "F.Paste")
			(net "P2E_MB_BMC_RX_R2_DN<0>")
		)
	)
	(footprint ""
		(layer "F.Cu")
		(at 400.558 -158.562548)
		(property "Reference" "PC1644"
			(at 0 0 0)
			(layer "F.SilkS")
			(hide yes)
			(effects
				(font
					(size 1.27 1.27)
				)
			)
		)
		(property "Value" ""
			(at 0 0 0)
			(layer "F.Fab")
			(effects
				(font
					(size 1.27 1.27)
				)
			)
		)
		(duplicate_pad_numbers_are_jumpers no)
		(fp_line
			(start 2.750058 0.999998)
			(end -2.750058 0.999998)
			(stroke
				(width 0.1524)
				(type default)
			)
			(layer "F.SilkS")
		)
		(fp_circle
			(center 0 0.999998)
			(end 2.750058 0.999998)
			(stroke
				(width 0.1524)
				(type default)
			)
			(fill no)
			(layer "F.SilkS")
		)
		(fp_poly
			(pts
				(arc
					(start 2.750058 0.999998)
					(mid 0 3.750056)
					(end -2.750058 0.999998)
				)
			)
			(stroke
				(width 0)
				(type default)
			)
			(fill yes)
			(layer "F.SilkS")
		)
		(fp_circle
			(center 0 0.999998)
			(end 2.750058 0.999998)
			(stroke
				(width 0.1)
				(type default)
			)
			(fill no)
			(layer "F.Fab")
		)
		(pad "1" thru_hole rect
			(at 0 0)
			(size 1.5748 1.5748)
			(drill 1.0668)
			(layers "*.Cu" "*.Mask")
			(remove_unused_layers no)
			(net "PVCCD_HV_CPU0")
			(clearance 0)
			(padstack
				(mode front_inner_back)
				(layer "Inner"
					(shape circle)
					(size 1.5748 1.5748)
					(clearance 0)
				)
				(layer "B.Cu"
					(shape rect)
					(size 1.5748 1.5748)
					(clearance 0)
				)
			)
		)
		(pad "2" thru_hole circle
			(at 0 1.999996)
			(size 1.5748 1.5748)
			(drill 1.0668)
			(layers "*.Cu" "*.Mask")
			(remove_unused_layers no)
			(net "GND")
			(clearance 0)
		)
	)
	(footprint ""
		(layer "F.Cu")
		(at 109.337856 -31.49981)
		(property "Reference" "R3242"
			(at 0 0 0)
			(layer "F.SilkS")
			(hide yes)
			(effects
				(font
					(size 1.27 1.27)
				)
			)
		)
		(property "Value" ""
			(at 0 0 0)
			(layer "F.Fab")
			(effects
				(font
					(size 1.27 1.27)
				)
			)
		)
		(duplicate_pad_numbers_are_jumpers no)
		(fp_line
			(start -0.7874 -0.4064)
			(end 0.7874 -0.4064)
			(stroke
				(width 0.1524)
				(type default)
			)
			(layer "F.SilkS")
		)
		(fp_line
			(start -0.7874 0.4064)
			(end -0.7874 -0.4064)
			(stroke
				(width 0.1524)
				(type default)
			)
			(layer "F.SilkS")
		)
		(fp_line
			(start 0.7874 -0.4064)
			(end 0.7874 0.4064)
			(stroke
				(width 0.1524)
				(type default)
			)
			(layer "F.SilkS")
		)
		(fp_line
			(start 0.7874 0.4064)
			(end -0.7874 0.4064)
			(stroke
				(width 0.1524)
				(type default)
			)
			(layer "F.SilkS")
		)
		(fp_line
			(start -0.67945 -0.305054)
			(end -0.12065 -0.305054)
			(stroke
				(width 0.1)
				(type default)
			)
			(layer "F.Fab")
		)
		(fp_line
			(start -0.67945 0.3048)
			(end -0.67945 -0.305054)
			(stroke
				(width 0.1)
				(type default)
			)
			(layer "F.Fab")
		)
		(fp_line
			(start -0.12065 -0.305054)
			(end -0.12065 -0.2794)
			(stroke
				(width 0.1)
				(type default)
			)
			(layer "F.Fab")
		)
		(fp_line
			(start -0.12065 -0.2794)
			(end 0.12065 -0.2794)
			(stroke
				(width 0.1)
				(type default)
			)
			(layer "F.Fab")
		)
		(fp_line
			(start -0.12065 0.2794)
			(end -0.12065 0.3048)
			(stroke
				(width 0.1)
				(type default)
			)
			(layer "F.Fab")
		)
		(fp_line
			(start -0.12065 0.3048)
			(end -0.67945 0.3048)
			(stroke
				(width 0.1)
				(type default)
			)
			(layer "F.Fab")
		)
		(fp_line
			(start 0.120396 0.2794)
			(end -0.12065 0.2794)
			(stroke
				(width 0.1)
				(type default)
			)
			(layer "F.Fab")
		)
		(fp_line
			(start 0.120396 0.3048)
			(end 0.120396 0.2794)
			(stroke
				(width 0.1)
				(type default)
			)
			(layer "F.Fab")
		)
		(fp_line
			(start 0.12065 -0.3048)
			(end 0.67945 -0.3048)
			(stroke
				(width 0.1)
				(type default)
			)
			(layer "F.Fab")
		)
		(fp_line
			(start 0.12065 -0.2794)
			(end 0.12065 -0.3048)
			(stroke
				(width 0.1)
				(type default)
			)
			(layer "F.Fab")
		)
		(fp_line
			(start 0.67945 -0.3048)
			(end 0.67945 0.3048)
			(stroke
				(width 0.1)
				(type default)
			)
			(layer "F.Fab")
		)
		(fp_line
			(start 0.67945 0.3048)
			(end 0.120396 0.3048)
			(stroke
				(width 0.1)
				(type default)
			)
			(layer "F.Fab")
		)
		(pad "1" smd circle
			(at -0.40005 0)
			(size 0 0)
			(layers "F.Cu" "F.Mask" "F.Paste")
			(net "SMB_OCP_V3_2_3V3AUX_SCL")
		)
		(pad "2" smd circle
			(at 0.40005 0)
			(size 0 0)
			(layers "F.Cu" "F.Mask" "F.Paste")
			(net "P3V3_AUX")
		)
	)
	(footprint ""
		(layer "F.Cu")
		(at 204.93736 -118.074948 180)
		(property "Reference" "R4171"
			(at 0 0 180)
			(layer "F.SilkS")
			(hide yes)
			(effects
				(font
					(size 1.27 1.27)
				)
			)
		)
		(property "Value" ""
			(at 0 0 180)
			(layer "F.Fab")
			(effects
				(font
					(size 1.27 1.27)
				)
			)
		)
		(duplicate_pad_numbers_are_jumpers no)
		(fp_line
			(start 0.7874 0.4064)
			(end -0.7874 0.4064)
			(stroke
				(width 0.1524)
				(type default)
			)
			(layer "F.SilkS")
		)
		(fp_line
			(start 0.7874 -0.4064)
			(end 0.7874 0.4064)
			(stroke
				(width 0.1524)
				(type default)
			)
			(layer "F.SilkS")
		)
		(fp_line
			(start -0.7874 0.4064)
			(end -0.7874 -0.4064)
			(stroke
				(width 0.1524)
				(type default)
			)
			(layer "F.SilkS")
		)
		(fp_line
			(start -0.7874 -0.4064)
			(end 0.7874 -0.4064)
			(stroke
				(width 0.1524)
				(type default)
			)
			(layer "F.SilkS")
		)
		(fp_line
			(start 0.67945 0.3048)
			(end 0.120396 0.3048)
			(stroke
				(width 0.1)
				(type default)
			)
			(layer "F.Fab")
		)
		(fp_line
			(start 0.67945 -0.3048)
			(end 0.67945 0.3048)
			(stroke
				(width 0.1)
				(type default)
			)
			(layer "F.Fab")
		)
		(fp_line
			(start 0.12065 -0.2794)
			(end 0.12065 -0.3048)
			(stroke
				(width 0.1)
				(type default)
			)
			(layer "F.Fab")
		)
		(fp_line
			(start 0.12065 -0.3048)
			(end 0.67945 -0.3048)
			(stroke
				(width 0.1)
				(type default)
			)
			(layer "F.Fab")
		)
		(fp_line
			(start 0.120396 0.3048)
			(end 0.120396 0.2794)
			(stroke
				(width 0.1)
				(type default)
			)
			(layer "F.Fab")
		)
		(fp_line
			(start 0.120396 0.2794)
			(end -0.12065 0.2794)
			(stroke
				(width 0.1)
				(type default)
			)
			(layer "F.Fab")
		)
		(fp_line
			(start -0.12065 0.3048)
			(end -0.67945 0.3048)
			(stroke
				(width 0.1)
				(type default)
			)
			(layer "F.Fab")
		)
		(fp_line
			(start -0.12065 0.2794)
			(end -0.12065 0.3048)
			(stroke
				(width 0.1)
				(type default)
			)
			(layer "F.Fab")
		)
		(fp_line
			(start -0.12065 -0.2794)
			(end 0.12065 -0.2794)
			(stroke
				(width 0.1)
				(type default)
			)
			(layer "F.Fab")
		)
		(fp_line
			(start -0.12065 -0.305054)
			(end -0.12065 -0.2794)
			(stroke
				(width 0.1)
				(type default)
			)
			(layer "F.Fab")
		)
		(fp_line
			(start -0.67945 0.3048)
			(end -0.67945 -0.305054)
			(stroke
				(width 0.1)
				(type default)
			)
			(layer "F.Fab")
		)
		(fp_line
			(start -0.67945 -0.305054)
			(end -0.12065 -0.305054)
			(stroke
				(width 0.1)
				(type default)
			)
			(layer "F.Fab")
		)
		(pad "1" smd circle
			(at -0.40005 0 180)
			(size 0 0)
			(layers "F.Cu" "F.Mask" "F.Paste")
			(net "GPU_3V3IO_RSVD3_ISO")
		)
		(pad "2" smd circle
			(at 0.40005 0 180)
			(size 0 0)
			(layers "F.Cu" "F.Mask" "F.Paste")
			(net "GPU_3V3IO_RSVD3_ISO_R")
		)
	)
	(footprint ""
		(layer "F.Cu")
		(at 29.478478 -17.623536 90)
		(property "Reference" "C816"
			(at 0 0 90)
			(layer "F.SilkS")
			(hide yes)
			(effects
				(font
					(size 1.27 1.27)
				)
			)
		)
		(property "Value" ""
			(at 0 0 90)
			(layer "F.Fab")
			(effects
				(font
					(size 1.27 1.27)
				)
			)
		)
		(duplicate_pad_numbers_are_jumpers no)
		(fp_line
			(start 0.299974 -0.150114)
			(end 0.299974 0.150114)
			(stroke
				(width 0.1)
				(type default)
			)
			(layer "F.Fab")
		)
		(fp_line
			(start -0.299974 -0.150114)
			(end 0.299974 -0.150114)
			(stroke
				(width 0.1)
				(type default)
			)
			(layer "F.Fab")
		)
		(fp_line
			(start 0.299974 0.150114)
			(end -0.299974 0.150114)
			(stroke
				(width 0.1)
				(type default)
			)
			(layer "F.Fab")
		)
		(fp_line
			(start -0.299974 0.150114)
			(end -0.299974 -0.150114)
			(stroke
				(width 0.1)
				(type default)
			)
			(layer "F.Fab")
		)
		(pad "1" smd rect
			(at -0.2667 0 90)
			(size 0.3048 0.381)
			(layers "F.Cu" "F.Mask" "F.Paste")
			(net "P5E_CPU1_PE1_TX_C_DN<10>")
		)
		(pad "2" smd rect
			(at 0.2667 0 90)
			(size 0.3048 0.381)
			(layers "F.Cu" "F.Mask" "F.Paste")
			(net "P5E_CPU1_PE1_TX_DN<10>")
		)
	)
	(footprint ""
		(layer "F.Cu")
		(at 105.912158 -353.137724)
		(property "Reference" "PC549"
			(at 0 0 0)
			(layer "F.SilkS")
			(hide yes)
			(effects
				(font
					(size 1.27 1.27)
				)
			)
		)
		(property "Value" ""
			(at 0 0 0)
			(layer "F.Fab")
			(effects
				(font
					(size 1.27 1.27)
				)
			)
		)
		(duplicate_pad_numbers_are_jumpers no)
		(fp_line
			(start -0.7874 -0.4064)
			(end 0.7874 -0.4064)
			(stroke
				(width 0.1524)
				(type default)
			)
			(layer "F.SilkS")
		)
		(fp_line
			(start -0.7874 0.4064)
			(end -0.7874 -0.4064)
			(stroke
				(width 0.1524)
				(type default)
			)
			(layer "F.SilkS")
		)
		(fp_line
			(start 0.7874 -0.4064)
			(end 0.7874 0.4064)
			(stroke
				(width 0.1524)
				(type default)
			)
			(layer "F.SilkS")
		)
		(fp_line
			(start 0.7874 0.4064)
			(end -0.7874 0.4064)
			(stroke
				(width 0.1524)
				(type default)
			)
			(layer "F.SilkS")
		)
		(fp_line
			(start -0.67945 -0.305054)
			(end -0.12065 -0.305054)
			(stroke
				(width 0.1)
				(type default)
			)
			(layer "F.Fab")
		)
		(fp_line
			(start -0.67945 0.3048)
			(end -0.67945 -0.305054)
			(stroke
				(width 0.1)
				(type default)
			)
			(layer "F.Fab")
		)
		(fp_line
			(start -0.12065 -0.305054)
			(end -0.12065 -0.2794)
			(stroke
				(width 0.1)
				(type default)
			)
			(layer "F.Fab")
		)
		(fp_line
			(start -0.12065 -0.2794)
			(end 0.12065 -0.2794)
			(stroke
				(width 0.1)
				(type default)
			)
			(layer "F.Fab")
		)
		(fp_line
			(start -0.12065 0.2794)
			(end -0.12065 0.3048)
			(stroke
				(width 0.1)
				(type default)
			)
			(layer "F.Fab")
		)
		(fp_line
			(start -0.12065 0.3048)
			(end -0.67945 0.3048)
			(stroke
				(width 0.1)
				(type default)
			)
			(layer "F.Fab")
		)
		(fp_line
			(start 0.120396 0.2794)
			(end -0.12065 0.2794)
			(stroke
				(width 0.1)
				(type default)
			)
			(layer "F.Fab")
		)
		(fp_line
			(start 0.120396 0.3048)
			(end 0.120396 0.2794)
			(stroke
				(width 0.1)
				(type default)
			)
			(layer "F.Fab")
		)
		(fp_line
			(start 0.12065 -0.3048)
			(end 0.67945 -0.3048)
			(stroke
				(width 0.1)
				(type default)
			)
			(layer "F.Fab")
		)
		(fp_line
			(start 0.12065 -0.2794)
			(end 0.12065 -0.3048)
			(stroke
				(width 0.1)
				(type default)
			)
			(layer "F.Fab")
		)
		(fp_line
			(start 0.67945 -0.3048)
			(end 0.67945 0.3048)
			(stroke
				(width 0.1)
				(type default)
			)
			(layer "F.Fab")
		)
		(fp_line
			(start 0.67945 0.3048)
			(end 0.120396 0.3048)
			(stroke
				(width 0.1)
				(type default)
			)
			(layer "F.Fab")
		)
		(pad "1" smd circle
			(at -0.40005 0)
			(size 0 0)
			(layers "F.Cu" "F.Mask" "F.Paste")
			(net "SH_PVCCIN_CPU1_R")
		)
		(pad "2" smd circle
			(at 0.40005 0)
			(size 0 0)
			(layers "F.Cu" "F.Mask" "F.Paste")
			(net "VSENSE_PVCCIN_CPU1_DN")
		)
	)
)
